# Honeybadger_Riser_card_FR4_4Layer_Stack-up_20131107_v1EE.xlsx — Wistron (pcb-stackup)
| Board Number: |  |  | N/A |  |  |  |  |  |  |  |  |  |  |
| Project Name: |  |  | Honeybadger |  |  |  |  |  |  |  |  |  |  |
| Model Name: |  |  | Riser Card |  |  |  |  |  |  |  |  |  |  |
| Layer Count: |  |  | 4 Layer |  |  |  |  |  |  |  |  |  |  |
| Date: |  |  | 41585 |  |  |  | Sigle Ended Impedance Line Width |  |  | Differential Impedance Line Width / Separation |  |  |  |
| Material: |  |  | FR4(Lead-Free, OSP, Tg=150) |  |  | Imp | 50 |  | Imp | 85 |  |  |  |
| Customer: |  |  | Facebook |  |  | Variation | Inner /Outer ±5Ω |  | Variation | Inner 10% / Outer 10% |  |  |  |
| EE Engineer: |  |  | <name> |  |  | Bus | MISC |  | Bus | PCIe |  |  |  |
| SI Engineer: |  |  | <name> |  |  |  |  |  |  |  |  |  |  |
|  |  |  |  |  |  | Type | SE |  | Type | DP |  |  |  |
| Layer |  |  |  | Thickness | Er | Layers | 1,4 |  | Layers | 1,4 |  |  |  |
|  |  |  | Cu oz | Wistron | Wistron |  | Wistron |  |  | Wistron |  |  |  |
|  | Mask |  |  | 0.5 | 3.7 |  | Width | Width |  | Width | Space | Imp |  |
| S1 | Signal |  | 0.5 oz +plating | 1.9 |  | S1 | 4.25 | 50.33 | S1 | 5.5 | 8 | 84.83 | S1 |
|  | Prepreg |  |  | 2.7 | 3.5 |  |  |  |  |  |  |  |  |
| P2 | PWR | GND | 1 | 1.3 |  | P2 | reference layer |  | P2 | reference layer |  |  | P2 |
|  | Core |  |  | 50 | 4.7 |  |  |  |  |  |  |  |  |
| G3 | GND |  | 1 | 1.3 |  | G3 | reference layer |  | G3 | reference layer |  |  | G3 |
|  | Prepreg |  |  | 2.7 | 3.5 |  |  |  |  |  |  |  |  |
| S4 | Signal |  | 0.5 oz +plating | 1.9 |  | S4 | 4.25 | 50.33 | S4 | 5.5 | 8 | 84.83 | S4 |
|  | Mask |  |  | 0.5 | 3.7 |  |  |  |  |  |  |  |  |
| Target = 1.6 mm |  |  | mil | 62.8 |  |  |  |  |  |  |  |  |  |
|  |  |  | mm | 1.5951231902463805 |  |  |  |  |  |  |  |  |  |
| Note: | 1. Unit is mil |  |  |  |  |  |  |  |  |  |  |  |  |
|  | 2. The variation of total thickness is Target±10% |  |  |  |  |  |  |  |  |  |  |  |  |
|  | 3. The total thickness includes trace and solder mask , not G/F  area |  |  |  |  |  |  |  |  |  |  |  |  |
|  | 4. Minimum via hole copper thickness is 1.0 mil |  |  |  |  |  |  |  |  |  |  |  |  |
|  | 5. Minimum surface copper thickness 1.5 mil |  |  |  |  |  |  |  |  |  |  |  |  |
|  | 6.W1/W2 were define as below. |  |  |  |  |  |  |  |  |  |  |  |  |
